# S9S_MB_2U (Grand Teton) — schematic netlist excerpt (pin names and nets, part order shuffled) for the footprints in the layout excerpt that follows; sources: Cadence DE-HDL packaged netlist, KiCad conversion of 03242023_DA0F0TMBIJ0_F0T_Motherboard_J_brd_V01_OCP.brd

J25  SCONN288_ADR50017P130CC  SCONN288_ADR50017-P130CC IO  pkg DDR288S_1-1VXB  page 106
  VIN_BULK0  = P12V_S3_AUX_CPU1_NVDIMM
  RFU0  = TP_CHE_CPU1_DIMM1_FRU_0
  VIN_MGMT  = P3V3_AUX
  HSCL  = I3C_SPD_DDREFGH_CPU1_LVC1_SCL_R
  HSDA  = I3C_SPD_DDREFGH_CPU1_LVC1_SDA
  VSS0  = GND
  DQ0_A  = M_E_CPU1_SA_DQ<0>
  VSS1  = GND
  DQ1_A  = M_E_CPU1_SA_DQ<1>
  VSS2  = GND
  DQS0_A_T  = M_E_CPU1_SA_DQS_DP<0>
  DQS0_A_C  = M_E_CPU1_SA_DQS_DN<0>
  VSS3  = GND
  DQ4_A  = M_E_CPU1_SA_DQ<4>
  VSS4  = GND
  DQ5_A  = M_E_CPU1_SA_DQ<5>
  VSS5  = GND
  DQ8_A  = M_E_CPU1_SA_DQ<8>
  VSS6  = GND
  DQ9_A  = M_E_CPU1_SA_DQ<9>
  VSS7  = GND
  DQS1_A_T  = M_E_CPU1_SA_DQS_DP<1>
  DQS1_A_C  = M_E_CPU1_SA_DQS_DN<1>
  VSS8  = GND
  DQ12_A  = M_E_CPU1_SA_DQ<12>
  VSS9  = GND
  DQ13_A  = M_E_CPU1_SA_DQ<13>
  VSS10  = GND
  DQ16_A  = M_E_CPU1_SA_DQ<16>
  VSS11  = GND
  DQ17_A  = M_E_CPU1_SA_DQ<17>
  VSS12  = GND
  DQS2_A_T  = M_E_CPU1_SA_DQS_DP<2>
  DQS2_A_C  = M_E_CPU1_SA_DQS_DN<2>
  VSS13  = GND
  DQ20_A  = M_E_CPU1_SA_DQ<20>
  VSS14  = GND
  DQ21_A  = M_E_CPU1_SA_DQ<21>
  VSS15  = GND
  DQ24_A  = M_E_CPU1_SA_DQ<24>
  VSS16  = GND
  DQ25_A  = M_E_CPU1_SA_DQ<25>
  VSS17  = GND
  DQS3_A_T  = M_E_CPU1_SA_DQS_DP<3>
  DQS3_A_C  = M_E_CPU1_SA_DQS_DN<3>
  VSS18  = GND
  DQ28_A  = M_E_CPU1_SA_DQ<28>
  VSS19  = GND
  DQ29_A  = M_E_CPU1_SA_DQ<29>
  VSS20  = GND
  CB0_A  = M_E_CPU1_SA_CB<0>
  VSS21  = GND
  CB1_A  = M_E_CPU1_SA_CB<1>
  VSS22  = GND
  DQS4_A_T  = M_E_CPU1_SA_DQS_DP<4>
  DQS4_A_C  = M_E_CPU1_SA_DQS_DN<4>
  VSS23  = GND
  CB4_A  = M_E_CPU1_SA_CB<4>
  VSS24  = GND
  CB5_A  = M_E_CPU1_SA_CB<5>
  VSS25  = GND
  ALERT_N  = M_E_CPU1_ALERT_N
  VSS26  = GND
  CS0_A_N  = M_E_CPU1_SA_CS_N<0>
  VSS27  = GND
  CA0_A  = M_E_CPU1_SA_CA<0>
  VSS28  = GND
  CA2_A  = M_E_CPU1_SA_CA<2>
  VSS29  = GND
  CA4_A  = M_E_CPU1_SA_CA<4>
  VSS30  = GND
  CA6_A  = M_E_CPU1_SA_CA<6>
  VSS31  = GND
  PAR_A  = M_E_CPU1_SA_PAR
  VSS32  = GND
  CA0_B  = M_E_CPU1_SB_CA<0>
  VSS33  = GND
  CA2_B  = M_E_CPU1_SB_CA<2>
  VSS34  = GND
  CA4_B  = M_E_CPU1_SB_CA<4>
  VSS35  = GND
  CA6_B  = M_E_CPU1_SB_CA<6>
  VSS36  = GND
  CS0_B_N  = M_E_CPU1_SB_CS_N<0>
  VSS37  = GND
  \lbd||rsp_a_n\  = M_E_CPU1_SA_RSP<0>
  \lbs||rsp_b_n\  = M_E_CPU1_SB_RSP<0>
  VSS38  = GND
  CB4_B  = M_E_CPU1_SB_CB<4>
  VSS39  = GND
  CB5_B  = M_E_CPU1_SB_CB<5>
  VSS40  = GND
  \dqs9_b_t||tdqs9_b_t||dbi4_b_n\  = M_E_CPU1_SB_DQS_DP<9>
  \dqs9_b_c||tdqs9_b_c\  = M_E_CPU1_SB_DQS_DN<9>
  VSS41  = GND
  CB0_B  = M_E_CPU1_SB_CB<0>
  VSS42  = GND
  CB1_B  = M_E_CPU1_SB_CB<1>
  VSS43  = GND
  DQ0_B  = M_E_CPU1_SB_DQ<0>
  VSS44  = GND
  DQ1_B  = M_E_CPU1_SB_DQ<1>
  VSS45  = GND
  DQS0_B_T  = M_E_CPU1_SB_DQS_DP<0>
  DQS0_B_C  = M_E_CPU1_SB_DQS_DN<0>
  VSS46  = GND
  DQ4_B  = M_E_CPU1_SB_DQ<4>
  VSS47  = GND
  DQ5_B  = M_E_CPU1_SB_DQ<5>
  VSS48  = GND
  DQ8_B  = M_E_CPU1_SB_DQ<8>
  VSS49  = GND
  DQ9_B  = M_E_CPU1_SB_DQ<9>
  VSS50  = GND
  DQS1_B_T  = M_E_CPU1_SB_DQS_DP<1>
  DQS1_B_C  = M_E_CPU1_SB_DQS_DN<1>
  VSS51  = GND
  DQ12_B  = M_E_CPU1_SB_DQ<12>
  VSS52  = GND
  DQ13_B  = M_E_CPU1_SB_DQ<13>
  VSS53  = GND
  DQ16_B  = M_E_CPU1_SB_DQ<16>
  VSS54  = GND
  DQ17_B  = M_E_CPU1_SB_DQ<17>
  VSS55  = GND
  DQS2_B_T  = M_E_CPU1_SB_DQS_DP<2>
  DQS2_B_C  = M_E_CPU1_SB_DQS_DN<2>
  VSS56  = GND
  DQ20_B  = M_E_CPU1_SB_DQ<20>
  VSS57  = GND
  DQ21_B  = M_E_CPU1_SB_DQ<21>
  VSS58  = GND
  DQ24_B  = M_E_CPU1_SB_DQ<24>
  VSS59  = GND
  DQ25_B  = M_E_CPU1_SB_DQ<25>
  VSS60  = GND
  DQS3_B_T  = M_E_CPU1_SB_DQS_DP<3>
  DQS3_B_C  = M_E_CPU1_SB_DQS_DN<3>
  VSS61  = GND
  DQ28_B  = M_E_CPU1_SB_DQ<28>
  VSS62  = GND
  DQ29_B  = M_E_CPU1_SB_DQ<29>
  VSS63  = GND
  RFU1  = TP_CHE_CPU1_DIMM1_FRU_1
  VIN_BULK1  = P12V_S3_AUX_CPU1_NVDIMM
  VIN_BULK2  = P12V_S3_AUX_CPU1_NVDIMM
  \pwr_good||fail_n\  = PWRGD_CHE_CPU1_DIMM1
  HSA  = PD_CHE_CPU1_DIMM1_SAA
  RFU2  = TP_CHE_CPU1_DIMM1_FRU_2
  RFU3  = TP_CHE_CPU1_DIMM1_FRU_3
  VSS64  = GND
  DQ2_A  = M_E_CPU1_SA_DQ<2>
  VSS65  = GND
  DQ3_A  = M_E_CPU1_SA_DQ<3>
  VSS66  = GND
  \dqs5_a_c||tdqs5_a_c||dqs5_a_t||tdqs5_a_t\  = M_E_CPU1_SA_DQS_DN<5>
  \dqs5_a_t||tdqs5_a_t\  = M_E_CPU1_SA_DQS_DP<5>
  VSS67  = GND
  DQ6_A  = M_E_CPU1_SA_DQ<6>
  VSS68  = GND
  DQ7_A  = M_E_CPU1_SA_DQ<7>
  VSS69  = GND
  DQ10_A  = M_E_CPU1_SA_DQ<10>
  VSS70  = GND
  DQ11_A  = M_E_CPU1_SA_DQ<11>
  VSS71  = GND
  \dqs6_a_c||tdqs6_a_c||dqs6_a_t||tdqs6_a_t\  = M_E_CPU1_SA_DQS_DN<6>
  \dqs6_a_t||tdqs6_a_t\  = M_E_CPU1_SA_DQS_DP<6>
  VSS72  = GND
  DQ14_A  = M_E_CPU1_SA_DQ<14>
  VSS73  = GND
  DQ15_A  = M_E_CPU1_SA_DQ<15>
  VSS74  = GND
  DQ18_A  = M_E_CPU1_SA_DQ<18>
  VSS75  = GND
  DQ19_A  = M_E_CPU1_SA_DQ<19>
  VSS76  = GND
  \dqs7_a_c||tdqs7_a_c\  = M_E_CPU1_SA_DQS_DN<7>
  \dqs7_a_t||tdqs7_a_t\  = M_E_CPU1_SA_DQS_DP<7>
  VSS77  = GND
  DQ22_A  = M_E_CPU1_SA_DQ<22>
  VSS78  = GND
  DQ23_A  = M_E_CPU1_SA_DQ<23>
  VSS79  = GND
  DQ26_A  = M_E_CPU1_SA_DQ<26>
  VSS80  = GND
  DQ27_A  = M_E_CPU1_SA_DQ<27>
  VSS81  = GND
  \dqs8_a_c||tdqs8_a_c\  = M_E_CPU1_SA_DQS_DN<8>
  \dqs8_a_t||tdqs8_a_t\  = M_E_CPU1_SA_DQS_DP<8>
  VSS82  = GND
  DQ30_A  = M_E_CPU1_SA_DQ<30>
  VSS83  = GND
  DQ31_A  = M_E_CPU1_SA_DQ<31>
  VSS84  = GND
  CB2_A  = M_E_CPU1_SA_CB<2>
  VSS85  = GND
  CB3_A  = M_E_CPU1_SA_CB<3>
  VSS86  = GND
  \dqs9_a_c||tdqs9_a_c\  = M_E_CPU1_SA_DQS_DN<9>
  \dqs9_a_t||tdqs9_a_t\  = M_E_CPU1_SA_DQS_DP<9>
  VSS87  = GND
  CB6_A  = M_E_CPU1_SA_CB<6>
  VSS88  = GND
  CB7_A  = M_E_CPU1_SA_CB<7>
  VSS89  = GND
  RESET_N  = RST_M_EF_CPU1_FPGA_N
  VSS90  = GND
  CS1_A_N  = M_E_CPU1_SA_CS_N<1>
  VSS91  = GND
  CA1_A  = M_E_CPU1_SA_CA<1>
  VSS92  = GND
  CA3_A  = M_E_CPU1_SA_CA<3>
  VSS93  = GND
  CA5_A  = M_E_CPU1_SA_CA<5>
  VSS94  = GND
  CK_T  = M_E_CPU1_CLK_DP<0>
  CK_C  = M_E_CPU1_CLK_DN<0>
  VSS95  = GND
  RFU4  = TP_CHE_CPU1_DIMM1_FRU_4
  CA1_B  = M_E_CPU1_SB_CA<1>
  VSS96  = GND
  CA3_B  = M_E_CPU1_SB_CA<3>
  VSS97  = GND
  CA5_B  = M_E_CPU1_SB_CA<5>
  VSS98  = GND
  PAR_B  = M_E_CPU1_SB_PAR
  VSS99  = GND
  CS1_B_N  = M_E_CPU1_SB_CS_N<1>
  VSS100  = GND
  RFU5  = TP_CHE_CPU1_DIMM1_FRU_5
  RFU6  = TP_CHE_CPU1_DIMM1_FRU_6
  VSS101  = GND
  CB6_B  = M_E_CPU1_SB_CB<6>
  VSS102  = GND
  CB7_B  = M_E_CPU1_SB_CB<7>
  VSS103  = GND
  DQS4_B_C  = M_E_CPU1_SB_DQS_DN<4>
  DQS4_B_T  = M_E_CPU1_SB_DQS_DP<4>
  VSS104  = GND
  CB2_B  = M_E_CPU1_SB_CB<2>
  VSS105  = GND
  CB3_B  = M_E_CPU1_SB_CB<3>
  VSS106  = GND
  DQ2_B  = M_E_CPU1_SB_DQ<2>
  VSS107  = GND
  DQ3_B  = M_E_CPU1_SB_DQ<3>
  VSS108  = GND
  \dqs5_b_c||tdqs5_b_c\  = M_E_CPU1_SB_DQS_DN<5>
  \dqs5_b_t||tdqs5_b_t\  = M_E_CPU1_SB_DQS_DP<5>
  VSS109  = GND
  DQ6_B  = M_E_CPU1_SB_DQ<6>
  VSS110  = GND
  DQ7_B  = M_E_CPU1_SB_DQ<7>
  VSS111  = GND
  DQ10_B  = M_E_CPU1_SB_DQ<10>
  VSS112  = GND
  DQ11_B  = M_E_CPU1_SB_DQ<11>
  VSS113  = GND
  \dqs6_b_c||tdqs6_b_c\  = M_E_CPU1_SB_DQS_DN<6>
  \dqs6_b_t||tdqs6_b_t\  = M_E_CPU1_SB_DQS_DP<6>
  VSS114  = GND
  DQ14_B  = M_E_CPU1_SB_DQ<14>
  VSS115  = GND
  DQ15_B  = M_E_CPU1_SB_DQ<15>
  VSS116  = GND
  DQ18_B  = M_E_CPU1_SB_DQ<18>
  VSS117  = GND
  DQ19_B  = M_E_CPU1_SB_DQ<19>
  VSS118  = GND
  \dqs7_b_c||tdqs7_b_c\  = M_E_CPU1_SB_DQS_DN<7>
  \dqs7_b_t||tdqs7_b_t\  = M_E_CPU1_SB_DQS_DP<7>
  VSS119  = GND
  DQ22_B  = M_E_CPU1_SB_DQ<22>
  VSS120  = GND
  DQ23_B  = M_E_CPU1_SB_DQ<23>
  VSS121  = GND
  DQ26_B  = M_E_CPU1_SB_DQ<26>
  VSS122  = GND
  DQ27_B  = M_E_CPU1_SB_DQ<27>
  VSS123  = GND
  \dqs8_b_c||tdqs8_b_c\  = M_E_CPU1_SB_DQS_DN<8>
  \dqs8_b_t||tdqs8_b_t\  = M_E_CPU1_SB_DQS_DP<8>
  VSS124  = GND
  DQ30_B  = M_E_CPU1_SB_DQ<30>
  VSS125  = GND
  DQ31_B  = M_E_CPU1_SB_DQ<31>
  VSS126  = GND
  G1  = GND
  G2  = GND
  G3  = GND

(kicad_pcb
	(version 20260206)
	(generator "pcbnew")
	(generator_version "10.0")
	(general
		(thickness 1.6)
		(legacy_teardrops no)
	)
	(paper "A4")
	(title_block
		(title "03242023_DA0F0TMBIJ0_F0T_Motherboard_J_brd_V01_OCP.brd")
		(comment 1 "Grand Teton / footprint 2539 of 6105 (J25), pads 138-182 of 291")
	)
	(layers
		(0 "F.Cu" signal "TOP")
		(4 "In1.Cu" signal "GND")
		(6 "In2.Cu" signal "IN1")
		(8 "In3.Cu" signal "GND1")
		(10 "In4.Cu" signal "IN2")
		(12 "In5.Cu" signal "GND2")
		(14 "In6.Cu" signal "IN3")
		(16 "In7.Cu" signal "GND3")
		(18 "In8.Cu" signal "VCC")
		(20 "In9.Cu" signal "VCC1")
		(22 "In10.Cu" signal "GND4")
		(24 "In11.Cu" signal "IN4")
		(26 "In12.Cu" signal "GND5")
		(28 "In13.Cu" signal "IN5")
		(30 "In14.Cu" signal "GND6")
		(32 "In15.Cu" signal "IN6")
		(34 "In16.Cu" signal "GND7")
		(2 "B.Cu" signal "BOTTOM")
		(9 "F.Adhes" user "F.Adhesive")
		(11 "B.Adhes" user "B.Adhesive")
		(13 "F.Paste" user "Package Geometry/Pastemask Top")
		(15 "B.Paste" user "Package Geometry/Pastemask Bottom")
		(5 "F.SilkS" user "Ref Des/Silkscreen Top")
		(7 "B.SilkS" user "Ref Des/Silkscreen Bottom")
		(1 "F.Mask" user "Board Geometry/Soldermask Top")
		(3 "B.Mask" user "Board Geometry/Soldermask Bottom")
		(17 "Dwgs.User" user "User.Drawings")
		(19 "Cmts.User" user "User.Comments")
		(21 "Eco1.User" user "User.Eco1")
		(23 "Eco2.User" user "User.Eco2")
		(25 "Edge.Cuts" user "Board Geometry/Outline")
		(27 "Margin" user)
		(31 "F.CrtYd" user "Package Geometry/Place Bound Top")
		(29 "B.CrtYd" user "Package Geometry/Place Bound Bottom")
		(35 "F.Fab" user "Ref Des/Assembly Top")
		(33 "B.Fab" user "Ref Des/Assembly Bottom")
	)
	(footprint ""
		(layer "F.Cu")
		(at 168.40708 -258.091686)
		(property "Reference" "J25"
			(at -3.683 -81.702148 0)
			(unlocked yes)
			(layer "F.SilkS")
			(effects
				(font
					(size 0.7874 0.5842)
					(thickness 0.1524)
				)
				(justify left)
			)
		)
		(property "Value" ""
			(at 0 0 0)
			(layer "F.Fab")
			(effects
				(font
					(size 1.27 1.27)
				)
			)
		)
		(duplicate_pad_numbers_are_jumpers no)
		(pad "138" smd rect
			(at -2.050034 58.224928 270)
			(size 0.519938 1.4986)
			(layers "F.Cu" "F.Mask" "F.Paste")
			(net "M_E_CPU1_SB_DQS_DN<3>")
		)
		(pad "139" smd rect
			(at -2.050034 59.075066 270)
			(size 0.519938 1.4986)
			(layers "F.Cu" "F.Mask" "F.Paste")
			(net "GND")
		)
		(pad "140" smd rect
			(at -2.050034 59.92495 270)
			(size 0.519938 1.4986)
			(layers "F.Cu" "F.Mask" "F.Paste")
			(net "M_E_CPU1_SB_DQ<28>")
		)
		(pad "141" smd rect
			(at -2.050034 60.775088 270)
			(size 0.519938 1.4986)
			(layers "F.Cu" "F.Mask" "F.Paste")
			(net "GND")
		)
		(pad "142" smd rect
			(at -2.050034 61.624972 270)
			(size 0.519938 1.4986)
			(layers "F.Cu" "F.Mask" "F.Paste")
			(net "M_E_CPU1_SB_DQ<29>")
		)
		(pad "143" smd rect
			(at -2.050034 62.47511 270)
			(size 0.519938 1.4986)
			(layers "F.Cu" "F.Mask" "F.Paste")
			(net "GND")
		)
		(pad "144" smd rect
			(at -2.050034 63.324994 270)
			(size 0.519938 1.4986)
			(layers "F.Cu" "F.Mask" "F.Paste")
			(net "TP_CHE_CPU1_DIMM1_FRU_1")
		)
		(pad "145" smd rect
			(at 2.050034 -63.324994 270)
			(size 0.519938 1.4986)
			(layers "F.Cu" "F.Mask" "F.Paste")
			(net "P12V_S3_AUX_CPU1_NVDIMM")
		)
		(pad "146" smd rect
			(at 2.050034 -62.47511 270)
			(size 0.519938 1.4986)
			(layers "F.Cu" "F.Mask" "F.Paste")
			(net "P12V_S3_AUX_CPU1_NVDIMM")
		)
		(pad "147" smd rect
			(at 2.050034 -61.624972 270)
			(size 0.519938 1.4986)
			(layers "F.Cu" "F.Mask" "F.Paste")
			(net "PWRGD_CHE_CPU1_DIMM1")
		)
		(pad "148" smd rect
			(at 2.050034 -60.775088 270)
			(size 0.519938 1.4986)
			(layers "F.Cu" "F.Mask" "F.Paste")
			(net "PD_CHE_CPU1_DIMM1_SAA")
		)
		(pad "149" smd rect
			(at 2.050034 -59.92495 270)
			(size 0.519938 1.4986)
			(layers "F.Cu" "F.Mask" "F.Paste")
			(net "TP_CHE_CPU1_DIMM1_FRU_2")
		)
		(pad "150" smd rect
			(at 2.050034 -59.075066 270)
			(size 0.519938 1.4986)
			(layers "F.Cu" "F.Mask" "F.Paste")
			(net "TP_CHE_CPU1_DIMM1_FRU_3")
		)
		(pad "151" smd rect
			(at 2.050034 -58.224928 270)
			(size 0.519938 1.4986)
			(layers "F.Cu" "F.Mask" "F.Paste")
			(net "GND")
		)
		(pad "152" smd rect
			(at 2.050034 -57.375044 270)
			(size 0.519938 1.4986)
			(layers "F.Cu" "F.Mask" "F.Paste")
			(net "M_E_CPU1_SA_DQ<2>")
		)
		(pad "153" smd rect
			(at 2.050034 -56.524906 270)
			(size 0.519938 1.4986)
			(layers "F.Cu" "F.Mask" "F.Paste")
			(net "GND")
		)
		(pad "154" smd rect
			(at 2.050034 -55.675022 270)
			(size 0.519938 1.4986)
			(layers "F.Cu" "F.Mask" "F.Paste")
			(net "M_E_CPU1_SA_DQ<3>")
		)
		(pad "155" smd rect
			(at 2.050034 -54.824884 270)
			(size 0.519938 1.4986)
			(layers "F.Cu" "F.Mask" "F.Paste")
			(net "GND")
		)
		(pad "156" smd rect
			(at 2.050034 -53.975 270)
			(size 0.519938 1.4986)
			(layers "F.Cu" "F.Mask" "F.Paste")
			(net "M_E_CPU1_SA_DQS_DN<5>")
		)
		(pad "157" smd rect
			(at 2.050034 -53.125116 270)
			(size 0.519938 1.4986)
			(layers "F.Cu" "F.Mask" "F.Paste")
			(net "M_E_CPU1_SA_DQS_DP<5>")
		)
		(pad "158" smd rect
			(at 2.050034 -52.274978 270)
			(size 0.519938 1.4986)
			(layers "F.Cu" "F.Mask" "F.Paste")
			(net "GND")
		)
		(pad "159" smd rect
			(at 2.050034 -51.425094 270)
			(size 0.519938 1.4986)
			(layers "F.Cu" "F.Mask" "F.Paste")
			(net "M_E_CPU1_SA_DQ<6>")
		)
		(pad "160" smd rect
			(at 2.050034 -50.574956 270)
			(size 0.519938 1.4986)
			(layers "F.Cu" "F.Mask" "F.Paste")
			(net "GND")
		)
		(pad "161" smd rect
			(at 2.050034 -49.725072 270)
			(size 0.519938 1.4986)
			(layers "F.Cu" "F.Mask" "F.Paste")
			(net "M_E_CPU1_SA_DQ<7>")
		)
		(pad "162" smd rect
			(at 2.050034 -48.874934 270)
			(size 0.519938 1.4986)
			(layers "F.Cu" "F.Mask" "F.Paste")
			(net "GND")
		)
		(pad "163" smd rect
			(at 2.050034 -48.02505 270)
			(size 0.519938 1.4986)
			(layers "F.Cu" "F.Mask" "F.Paste")
			(net "M_E_CPU1_SA_DQ<10>")
		)
		(pad "164" smd rect
			(at 2.050034 -47.174912 270)
			(size 0.519938 1.4986)
			(layers "F.Cu" "F.Mask" "F.Paste")
			(net "GND")
		)
		(pad "165" smd rect
			(at 2.050034 -46.325028 270)
			(size 0.519938 1.4986)
			(layers "F.Cu" "F.Mask" "F.Paste")
			(net "M_E_CPU1_SA_DQ<11>")
		)
		(pad "166" smd rect
			(at 2.050034 -45.47489 270)
			(size 0.519938 1.4986)
			(layers "F.Cu" "F.Mask" "F.Paste")
			(net "GND")
		)
		(pad "167" smd rect
			(at 2.050034 -44.625006 270)
			(size 0.519938 1.4986)
			(layers "F.Cu" "F.Mask" "F.Paste")
			(net "M_E_CPU1_SA_DQS_DN<6>")
		)
		(pad "168" smd rect
			(at 2.050034 -43.775122 270)
			(size 0.519938 1.4986)
			(layers "F.Cu" "F.Mask" "F.Paste")
			(net "M_E_CPU1_SA_DQS_DP<6>")
		)
		(pad "169" smd rect
			(at 2.050034 -42.924984 270)
			(size 0.519938 1.4986)
			(layers "F.Cu" "F.Mask" "F.Paste")
			(net "GND")
		)
		(pad "170" smd rect
			(at 2.050034 -42.0751 270)
			(size 0.519938 1.4986)
			(layers "F.Cu" "F.Mask" "F.Paste")
			(net "M_E_CPU1_SA_DQ<14>")
		)
		(pad "171" smd rect
			(at 2.050034 -41.224962 270)
			(size 0.519938 1.4986)
			(layers "F.Cu" "F.Mask" "F.Paste")
			(net "GND")
		)
		(pad "172" smd rect
			(at 2.050034 -40.375078 270)
			(size 0.519938 1.4986)
			(layers "F.Cu" "F.Mask" "F.Paste")
			(net "M_E_CPU1_SA_DQ<15>")
		)
		(pad "173" smd rect
			(at 2.050034 -39.52494 270)
			(size 0.519938 1.4986)
			(layers "F.Cu" "F.Mask" "F.Paste")
			(net "GND")
		)
		(pad "174" smd rect
			(at 2.050034 -38.675056 270)
			(size 0.519938 1.4986)
			(layers "F.Cu" "F.Mask" "F.Paste")
			(net "M_E_CPU1_SA_DQ<18>")
		)
		(pad "175" smd rect
			(at 2.050034 -37.824918 270)
			(size 0.519938 1.4986)
			(layers "F.Cu" "F.Mask" "F.Paste")
			(net "GND")
		)
		(pad "176" smd rect
			(at 2.050034 -36.975034 270)
			(size 0.519938 1.4986)
			(layers "F.Cu" "F.Mask" "F.Paste")
			(net "M_E_CPU1_SA_DQ<19>")
		)
		(pad "177" smd rect
			(at 2.050034 -36.124896 270)
			(size 0.519938 1.4986)
			(layers "F.Cu" "F.Mask" "F.Paste")
			(net "GND")
		)
		(pad "178" smd rect
			(at 2.050034 -35.275012 270)
			(size 0.519938 1.4986)
			(layers "F.Cu" "F.Mask" "F.Paste")
			(net "M_E_CPU1_SA_DQS_DN<7>")
		)
		(pad "179" smd rect
			(at 2.050034 -34.425128 270)
			(size 0.519938 1.4986)
			(layers "F.Cu" "F.Mask" "F.Paste")
			(net "M_E_CPU1_SA_DQS_DP<7>")
		)
		(pad "180" smd rect
			(at 2.050034 -33.57499 270)
			(size 0.519938 1.4986)
			(layers "F.Cu" "F.Mask" "F.Paste")
			(net "GND")
		)
		(pad "181" smd rect
			(at 2.050034 -32.725106 270)
			(size 0.519938 1.4986)
			(layers "F.Cu" "F.Mask" "F.Paste")
			(net "M_E_CPU1_SA_DQ<22>")
		)
		(pad "182" smd rect
			(at 2.050034 -31.874968 270)
			(size 0.519938 1.4986)
			(layers "F.Cu" "F.Mask" "F.Paste")
			(net "GND")
		)
	)
)
